(kicad_pcb
	(version 20260206)
	(generator "pcbnew")
	(generator_version "10.0")
	(general
		(thickness 1.5755)
		(legacy_teardrops no)
	)
	(paper "A4")
	(title_block
		(title "gnss-neo-m9n — 844-XXXXX_FAB_NEO-M9N_MODULE.PcbDoc")
		(comment 1 "Time Appliance Project (Time Card) / footprints 27-31 of 33")
	)
	(layers
		(0 "F.Cu" signal "L01-Top Layer")
		(4 "In1.Cu" signal "L02-Inner Layer")
		(6 "In2.Cu" signal "L03-Inner Layer")
		(2 "B.Cu" signal "L04-Bottom Layer")
		(9 "F.Adhes" user "F.Adhesive")
		(11 "B.Adhes" user "B.Adhesive")
		(13 "F.Paste" user "Top Paste")
		(15 "B.Paste" user "Bottom Paste")
		(5 "F.SilkS" user "Top Overlay")
		(7 "B.SilkS" user "Bottom Overlay")
		(1 "F.Mask" user "Top Solder")
		(3 "B.Mask" user "Bottom Solder")
		(17 "Dwgs.User" user "User.Drawings")
		(19 "Cmts.User" user "User.Comments")
		(21 "Eco1.User" user "User.Eco1")
		(23 "Eco2.User" user "User.Eco2")
		(25 "Edge.Cuts" user)
		(27 "Margin" user)
		(31 "F.CrtYd" user "Top Courtyard")
		(29 "B.CrtYd" user "Bottom Courtyard")
		(35 "F.Fab" user "Top Component Outline")
		(33 "B.Fab" user "Bottom Component Outline 2")
		(39 "User.1" user "M01_PCB_Outline")
	)
	(footprint "MyLibrary:L0402"
		(layer "F.Cu")
		(at 125.70276 101.476095 90)
		(property "Reference" "L1"
			(at -0.422433 1.490145 0)
			(unlocked yes)
			(layer "F.SilkS")
			(effects
				(font
					(size 0.635 0.635)
					(thickness 0.1778)
				)
			)
		)
		(property "Value" "27nH 300mA 460mohm 0402"
			(at 12.962345 2.118183 90)
			(unlocked yes)
			(layer "F.SilkS")
			(hide yes)
			(effects
				(font
					(size 0.635 0.635)
					(thickness 0.1778)
				)
			)
		)
		(sheetname "846-XXXXX_SCH_NEO-M9N_MODULE_2_RECEIVER")
		(sheetfile "846-XXXXX_SCH_NEO-M9N_MODULE_2_RECEIVER.kicad_sch")
		(duplicate_pad_numbers_are_jumpers no)
		(fp_line
			(start 0.84279 -0.47866)
			(end 0.84279 0.48654)
			(stroke
				(width 0.1778)
				(type solid)
			)
			(layer "F.SilkS")
		)
		(fp_line
			(start -0.83361 -0.47866)
			(end 0.84279 -0.47866)
			(stroke
				(width 0.1778)
				(type solid)
			)
			(layer "F.SilkS")
		)
		(fp_line
			(start -0.83361 -0.47866)
			(end -0.83361 0.48654)
			(stroke
				(width 0.1778)
				(type solid)
			)
			(layer "F.SilkS")
		)
		(fp_line
			(start -0.83361 0.48654)
			(end 0.84279 0.48654)
			(stroke
				(width 0.1778)
				(type solid)
			)
			(layer "F.SilkS")
		)
		(pad "1" smd rect
			(at -0.4 0 90)
			(size 0.4 0.5)
			(layers "F.Cu" "F.Mask" "F.Paste")
			(net "NetC5_2")
		)
		(pad "2" smd rect
			(at 0.4 0 90)
			(size 0.4 0.5)
			(layers "F.Cu" "F.Mask" "F.Paste")
			(net "RF_ANT")
		)
	)
	(footprint "MyLibrary:c0402"
		(layer "F.Cu")
		(at 151.67081 114.176095 90)
		(property "Reference" "C2"
			(at -3.083605 -0.072443 270)
			(unlocked yes)
			(layer "F.SilkS")
			(effects
				(font
					(size 0.635 0.635)
					(thickness 0.1778)
				)
			)
		)
		(property "Value" "100nF 10V 0402"
			(at 5.700245 2.118183 90)
			(unlocked yes)
			(layer "F.SilkS")
			(hide yes)
			(effects
				(font
					(size 0.635 0.635)
					(thickness 0.1778)
				)
			)
		)
		(sheetname "846-XXXXX_SCH_NEO-M9N_MODULE_2_RECEIVER")
		(sheetfile "846-XXXXX_SCH_NEO-M9N_MODULE_2_RECEIVER.kicad_sch")
		(duplicate_pad_numbers_are_jumpers no)
		(fp_line
			(start 0.9906 -0.4826)
			(end 0.9906 0.4826)
			(stroke
				(width 0.1778)
				(type solid)
			)
			(layer "F.SilkS")
		)
		(fp_line
			(start -0.9906 -0.4826)
			(end 0.9906 -0.4826)
			(stroke
				(width 0.1778)
				(type solid)
			)
			(layer "F.SilkS")
		)
		(fp_line
			(start -0.9906 -0.4826)
			(end -0.9906 0.4826)
			(stroke
				(width 0.1778)
				(type solid)
			)
			(layer "F.SilkS")
		)
		(fp_line
			(start -0.9906 0.4826)
			(end 0.9906 0.4826)
			(stroke
				(width 0.1778)
				(type solid)
			)
			(layer "F.SilkS")
		)
		(pad "1" smd rect
			(at -0.5 0 90)
			(size 0.5 0.5)
			(layers "F.Cu" "F.Mask" "F.Paste")
			(net "GND")
		)
		(pad "2" smd rect
			(at 0.5 0 90)
			(size 0.5 0.5)
			(layers "F.Cu" "F.Mask" "F.Paste")
			(net "+3V3")
		)
	)
	(footprint "MyLibrary:r0402"
		(layer "F.Cu")
		(at 153.6151 95.476095 180)
		(property "Reference" "R10"
			(at -2.177805 -0.122443 0)
			(unlocked yes)
			(layer "F.SilkS")
			(effects
				(font
					(size 0.635 0.635)
					(thickness 0.1778)
				)
			)
		)
		(property "Value" "0 ohm 0402"
			(at 2.907155 2.168983 180)
			(unlocked yes)
			(layer "F.SilkS")
			(hide yes)
			(effects
				(font
					(size 0.635 0.635)
					(thickness 0.1778)
				)
			)
		)
		(sheetname "846-XXXXX_SCH_NEO-M9N_MODULE_2_RECEIVER")
		(sheetfile "846-XXXXX_SCH_NEO-M9N_MODULE_2_RECEIVER.kicad_sch")
		(duplicate_pad_numbers_are_jumpers no)
		(fp_line
			(start 0.9906 0.5334)
			(end -0.9906 0.5334)
			(stroke
				(width 0.1778)
				(type solid)
			)
			(layer "F.SilkS")
		)
		(fp_line
			(start 0.9906 -0.5334)
			(end 0.9906 0.5334)
			(stroke
				(width 0.1778)
				(type solid)
			)
			(layer "F.SilkS")
		)
		(fp_line
			(start 0.9906 -0.5334)
			(end -0.9906 -0.5334)
			(stroke
				(width 0.1778)
				(type solid)
			)
			(layer "F.SilkS")
		)
		(fp_line
			(start -0.9906 -0.5334)
			(end -0.9906 0.5334)
			(stroke
				(width 0.1778)
				(type solid)
			)
			(layer "F.SilkS")
		)
		(pad "1" smd rect
			(at -0.5 0 180)
			(size 0.5 0.6)
			(layers "F.Cu" "F.Mask" "F.Paste")
			(net "GND")
		)
		(pad "2" smd rect
			(at 0.5 0 180)
			(size 0.5 0.6)
			(layers "F.Cu" "F.Mask" "F.Paste")
			(net "D_SEL")
		)
	)
	(footprint "MyLibrary:TP1MM"
		(layer "F.Cu")
		(at 151.5151 97.076095)
		(property "Reference" "TP1"
			(at 0.022443 -1.877805 90)
			(unlocked yes)
			(layer "F.SilkS")
			(effects
				(font
					(size 0.635 0.635)
					(thickness 0.1778)
				)
			)
		)
		(property "Value" "1MM"
			(at -2.092783 1.790085 270)
			(unlocked yes)
			(layer "F.SilkS")
			(hide yes)
			(effects
				(font
					(size 0.635 0.635)
					(thickness 0.1778)
				)
			)
		)
		(sheetname "846-XXXXX_SCH_NEO-M9N_MODULE_2_RECEIVER")
		(sheetfile "846-XXXXX_SCH_NEO-M9N_MODULE_2_RECEIVER.kicad_sch")
		(duplicate_pad_numbers_are_jumpers no)
		(pad "1" smd circle
			(at 0 0)
			(size 1 1)
			(layers "F.Cu" "F.Mask" "F.Paste")
			(net "D_SEL")
			(solder_paste_margin -100)
			(thermal_bridge_angle 90)
		)
	)
	(footprint "MyLibrary:IC_NEO-M9N"
		(layer "F.Cu")
		(at 145.6151 105.376095 90)
		(property "Reference" "U1"
			(at -6.722433 -8.722205 0)
			(unlocked yes)
			(layer "F.SilkS")
			(effects
				(font
					(size 0.635 0.635)
					(thickness 0.1778)
				)
			)
		)
		(property "Value" "NEO-M9N-00B"
			(at -1.74154 9.661983 90)
			(unlocked yes)
			(layer "F.SilkS")
			(hide yes)
			(effects
				(font
					(size 0.635 0.635)
					(thickness 0.1778)
				)
			)
		)
		(sheetname "846-XXXXX_SCH_NEO-M9N_MODULE_2_RECEIVER")
		(sheetfile "846-XXXXX_SCH_NEO-M9N_MODULE_2_RECEIVER.kicad_sch")
		(duplicate_pad_numbers_are_jumpers no)
		(fp_line
			(start 7.1755 -8.025)
			(end 7.1755 8.025)
			(stroke
				(width 0.1778)
				(type solid)
			)
			(layer "F.SilkS")
		)
		(fp_line
			(start -7.1755 -8.025)
			(end 7.1755 -8.025)
			(stroke
				(width 0.1778)
				(type solid)
			)
			(layer "F.SilkS")
		)
		(fp_line
			(start -7.1755 -8.025)
			(end -7.1755 8.025)
			(stroke
				(width 0.1778)
				(type solid)
			)
			(layer "F.SilkS")
		)
		(fp_line
			(start -7.1755 8.025)
			(end 7.1755 8.025)
			(stroke
				(width 0.1778)
				(type solid)
			)
			(layer "F.SilkS")
		)
		(fp_rect
			(start 3.699995 8.024995)
			(end 7.175485 7.574995)
			(stroke
				(width 0)
				(type default)
			)
			(fill yes)
			(layer "F.SilkS")
		)
		(fp_rect
			(start -5.80173 -7.40106)
			(end -7.00823 -6.60096)
			(stroke
				(width 0)
				(type default)
			)
			(fill yes)
			(layer "F.Paste")
		)
		(fp_rect
			(start -4.915905 -7.299465)
			(end -5.811255 -6.702565)
			(stroke
				(width 0)
				(type default)
			)
			(fill yes)
			(layer "F.Paste")
		)
		(fp_rect
			(start 4.915535 -6.702575)
			(end 5.810885 -7.299475)
			(stroke
				(width 0)
				(type default)
			)
			(fill yes)
			(layer "F.Paste")
		)
		(fp_rect
			(start 5.80136 -6.60098)
			(end 7.00786 -7.40108)
			(stroke
				(width 0)
				(type default)
			)
			(fill yes)
			(layer "F.Paste")
		)
		(fp_rect
			(start -5.80174 -6.30108)
			(end -7.00824 -5.50098)
			(stroke
				(width 0)
				(type default)
			)
			(fill yes)
			(layer "F.Paste")
		)
		(fp_rect
			(start -4.915915 -6.199485)
			(end -5.811265 -5.602585)
			(stroke
				(width 0)
				(type default)
			)
			(fill yes)
			(layer "F.Paste")
		)
		(fp_rect
			(start 4.915535 -5.602585)
			(end 5.810885 -6.199485)
			(stroke
				(width 0)
				(type default)
			)
			(fill yes)
			(layer "F.Paste")
		)
		(fp_rect
			(start 5.80136 -5.50098)
			(end 7.00786 -6.30108)
			(stroke
				(width 0)
				(type default)
			)
			(fill yes)
			(layer "F.Paste")
		)
		(fp_rect
			(start -5.80173 -5.20106)
			(end -7.00823 -4.40096)
			(stroke
				(width 0)
				(type default)
			)
			(fill yes)
			(layer "F.Paste")
		)
		(fp_rect
			(start -4.915905 -5.099465)
			(end -5.811255 -4.502565)
			(stroke
				(width 0)
				(type default)
			)
			(fill yes)
			(layer "F.Paste")
		)
		(fp_rect
			(start 4.915535 -4.502575)
			(end 5.810885 -5.099475)
			(stroke
				(width 0)
				(type default)
			)
			(fill yes)
			(layer "F.Paste")
		)
		(fp_rect
			(start 5.80136 -4.40098)
			(end 7.00786 -5.20108)
			(stroke
				(width 0)
				(type default)
			)
			(fill yes)
			(layer "F.Paste")
		)
		(fp_rect
			(start -5.80174 -4.10108)
			(end -7.00824 -3.30098)
			(stroke
				(width 0)
				(type default)
			)
			(fill yes)
			(layer "F.Paste")
		)
		(fp_rect
			(start -4.915915 -3.999475)
			(end -5.811265 -3.402575)
			(stroke
				(width 0)
				(type default)
			)
			(fill yes)
			(layer "F.Paste")
		)
		(fp_rect
			(start 4.915535 -3.402575)
			(end 5.810885 -3.999475)
			(stroke
				(width 0)
				(type default)
			)
			(fill yes)
			(layer "F.Paste")
		)
		(fp_rect
			(start 5.80136 -3.30098)
			(end 7.00786 -4.10108)
			(stroke
				(width 0)
				(type default)
			)
			(fill yes)
			(layer "F.Paste")
		)
		(fp_rect
			(start -5.80174 -3.00108)
			(end -7.00824 -2.20098)
			(stroke
				(width 0)
				(type default)
			)
			(fill yes)
			(layer "F.Paste")
		)
		(fp_rect
			(start -4.915915 -2.899485)
			(end -5.811265 -2.302585)
			(stroke
				(width 0)
				(type default)
			)
			(fill yes)
			(layer "F.Paste")
		)
		(fp_rect
			(start 4.915535 -2.302585)
			(end 5.810885 -2.899485)
			(stroke
				(width 0)
				(type default)
			)
			(fill yes)
			(layer "F.Paste")
		)
		(fp_rect
			(start 5.80136 -2.20098)
			(end 7.00786 -3.00108)
			(stroke
				(width 0)
				(type default)
			)
			(fill yes)
			(layer "F.Paste")
		)
		(fp_rect
			(start -5.80174 -0.00108)
			(end -7.00824 0.79902)
			(stroke
				(width 0)
				(type default)
			)
			(fill yes)
			(layer "F.Paste")
		)
		(fp_rect
			(start -4.915925 0.100515)
			(end -5.811275 0.697415)
			(stroke
				(width 0)
				(type default)
			)
			(fill yes)
			(layer "F.Paste")
		)
		(fp_rect
			(start 4.915515 0.697405)
			(end 5.810865 0.100505)
			(stroke
				(width 0)
				(type default)
			)
			(fill yes)
			(layer "F.Paste")
		)
		(fp_rect
			(start 5.80136 0.79902)
			(end 7.00786 -0.00108)
			(stroke
				(width 0)
				(type default)
			)
			(fill yes)
			(layer "F.Paste")
		)
		(fp_rect
			(start -5.80174 1.09892)
			(end -7.00824 1.89902)
			(stroke
				(width 0)
				(type default)
			)
			(fill yes)
			(layer "F.Paste")
		)
		(fp_rect
			(start -4.915915 1.200515)
			(end -5.811265 1.797415)
			(stroke
				(width 0)
				(type default)
			)
			(fill yes)
			(layer "F.Paste")
		)
		(fp_rect
			(start 4.915535 1.797415)
			(end 5.810885 1.200515)
			(stroke
				(width 0)
				(type default)
			)
			(fill yes)
			(layer "F.Paste")
		)
		(fp_rect
			(start 5.80136 1.89902)
			(end 7.00786 1.09892)
			(stroke
				(width 0)
				(type default)
			)
			(fill yes)
			(layer "F.Paste")
		)
		(fp_rect
			(start -5.80175 2.19892)
			(end -7.00825 2.99902)
			(stroke
				(width 0)
				(type default)
			)
			(fill yes)
			(layer "F.Paste")
		)
		(fp_rect
			(start -4.915925 2.300515)
			(end -5.811275 2.897415)
			(stroke
				(width 0)
				(type default)
			)
			(fill yes)
			(layer "F.Paste")
		)
		(fp_rect
			(start 4.915515 2.897405)
			(end 5.810865 2.300505)
			(stroke
				(width 0)
				(type default)
			)
			(fill yes)
			(layer "F.Paste")
		)
		(fp_rect
			(start 5.80134 2.999)
			(end 7.00784 2.1989)
			(stroke
				(width 0)
				(type default)
			)
			(fill yes)
			(layer "F.Paste")
		)
		(fp_rect
			(start -5.80175 3.29892)
			(end -7.00825 4.09902)
			(stroke
				(width 0)
				(type default)
			)
			(fill yes)
			(layer "F.Paste")
		)
		(fp_rect
			(start -4.915925 3.400515)
			(end -5.811275 3.997415)
			(stroke
				(width 0)
				(type default)
			)
			(fill yes)
			(layer "F.Paste")
		)
		(fp_rect
			(start 4.915515 3.997405)
			(end 5.810865 3.400505)
			(stroke
				(width 0)
				(type default)
			)
			(fill yes)
			(layer "F.Paste")
		)
		(fp_rect
			(start 5.80134 4.099)
			(end 7.00784 3.2989)
			(stroke
				(width 0)
				(type default)
			)
			(fill yes)
			(layer "F.Paste")
		)
		(fp_rect
			(start -5.80174 4.39892)
			(end -7.00824 5.19902)
			(stroke
				(width 0)
				(type default)
			)
			(fill yes)
			(layer "F.Paste")
		)
		(fp_rect
			(start -4.915915 4.500515)
			(end -5.811265 5.097415)
			(stroke
				(width 0)
				(type default)
			)
			(fill yes)
			(layer "F.Paste")
		)
		(fp_rect
			(start 4.915535 5.097415)
			(end 5.810885 4.500515)
			(stroke
				(width 0)
				(type default)
			)
			(fill yes)
			(layer "F.Paste")
		)
		(fp_rect
			(start 5.80136 5.19902)
			(end 7.00786 4.39892)
			(stroke
				(width 0)
				(type default)
			)
			(fill yes)
			(layer "F.Paste")
		)
		(fp_rect
			(start -5.80175 5.49892)
			(end -7.00825 6.29902)
			(stroke
				(width 0)
				(type default)
			)
			(fill yes)
			(layer "F.Paste")
		)
		(fp_rect
			(start -4.915925 5.600515)
			(end -5.811275 6.197415)
			(stroke
				(width 0)
				(type default)
			)
			(fill yes)
			(layer "F.Paste")
		)
		(fp_rect
			(start 4.915515 6.197405)
			(end 5.810865 5.600505)
			(stroke
				(width 0)
				(type default)
			)
			(fill yes)
			(layer "F.Paste")
		)
		(fp_rect
			(start 5.80134 6.299)
			(end 7.00784 5.4989)
			(stroke
				(width 0)
				(type default)
			)
			(fill yes)
			(layer "F.Paste")
		)
		(fp_rect
			(start -5.80174 6.59892)
			(end -7.00824 7.39902)
			(stroke
				(width 0)
				(type default)
			)
			(fill yes)
			(layer "F.Paste")
		)
		(fp_rect
			(start -4.915915 6.700515)
			(end -5.811265 7.297415)
			(stroke
				(width 0)
				(type default)
			)
			(fill yes)
			(layer "F.Paste")
		)
		(fp_rect
			(start 4.915535 7.297415)
			(end 5.810885 6.700515)
			(stroke
				(width 0)
				(type default)
			)
			(fill yes)
			(layer "F.Paste")
		)
		(fp_rect
			(start 5.80136 7.39902)
			(end 7.00786 6.59892)
			(stroke
				(width 0)
				(type default)
			)
			(fill yes)
			(layer "F.Paste")
		)
		(pad "1" smd rect
			(at 6.09981 6.99897 90)
			(size 1.79832 0.8001)
			(layers "F.Cu" "F.Mask" "F.Paste")
			(net "SAFEBOOT_N")
			(solder_paste_margin -2147.48364)
		)
		(pad "2" smd rect
			(at 6.09981 5.89915 90)
			(size 1.79832 0.8001)
			(layers "F.Cu" "F.Mask" "F.Paste")
			(net "D_SEL")
			(solder_paste_margin -2147.48364)
		)
		(pad "3" smd rect
			(at 6.09981 4.79933 90)
			(size 1.79832 0.8001)
			(layers "F.Cu" "F.Mask" "F.Paste")
			(net "TP1")
			(solder_paste_margin -2147.48364)
		)
		(pad "4" smd rect
			(at 6.09981 3.69951 90)
			(size 1.79832 0.8001)
			(layers "F.Cu" "F.Mask" "F.Paste")
			(net "EXTIN")
			(solder_paste_margin -2147.48364)
		)
		(pad "5" smd rect
			(at 6.09981 2.59969 90)
			(size 1.79832 0.8001)
			(layers "F.Cu" "F.Mask" "F.Paste")
			(net "USB_DM")
			(solder_paste_margin -2147.48364)
		)
		(pad "6" smd rect
			(at 6.09981 1.49987 90)
			(size 1.79832 0.8001)
			(layers "F.Cu" "F.Mask" "F.Paste")
			(net "USB_DP")
			(solder_paste_margin -2147.48364)
		)
		(pad "7" smd rect
			(at 6.09981 0.40005 90)
			(size 1.79832 0.8001)
			(layers "F.Cu" "F.Mask" "F.Paste")
			(net "VDD_USB")
			(solder_paste_margin -2147.48364)
		)
		(pad "8" smd rect
			(at 6.09981 -2.59969 90)
			(size 1.79832 0.8001)
			(layers "F.Cu" "F.Mask" "F.Paste")
			(net "RST_GPS")
			(solder_paste_margin -2147.48364)
		)
		(pad "9" smd rect
			(at 6.09981 -3.69951 90)
			(size 1.79832 0.8001)
			(layers "F.Cu" "F.Mask" "F.Paste")
			(solder_paste_margin -2147.48364)
		)
		(pad "10" smd rect
			(at 6.09981 -4.79933 90)
			(size 1.79832 0.8001)
			(layers "F.Cu" "F.Mask" "F.Paste")
			(net "GND")
			(solder_paste_margin -2147.48364)
		)
		(pad "11" smd rect
			(at 6.09981 -5.89915 90)
			(size 1.79832 0.8001)
			(layers "F.Cu" "F.Mask" "F.Paste")
			(net "RF_MODULE")
			(solder_paste_margin -2147.48364)
		)
		(pad "12" smd rect
			(at 6.09981 -6.99897 90)
			(size 1.79832 0.8001)
			(layers "F.Cu" "F.Mask" "F.Paste")
			(net "GND")
			(solder_paste_margin -2147.48364)
		)
		(pad "13" smd rect
			(at -6.09981 -6.99897 90)
			(size 1.79832 0.8001)
			(layers "F.Cu" "F.Mask" "F.Paste")
			(net "GND")
			(solder_paste_margin -2147.48364)
		)
		(pad "14" smd rect
			(at -6.09981 -5.89915 90)
			(size 1.79832 0.8001)
			(layers "F.Cu" "F.Mask" "F.Paste")
			(net "LNA_EN")
			(solder_paste_margin -2147.48364)
		)
		(pad "15" smd rect
			(at -6.09981 -4.79933 90)
			(size 1.79832 0.8001)
			(layers "F.Cu" "F.Mask" "F.Paste")
			(solder_paste_margin -2147.48364)
		)
		(pad "16" smd rect
			(at -6.09981 -3.69951 90)
			(size 1.79832 0.8001)
			(layers "F.Cu" "F.Mask" "F.Paste")
			(solder_paste_margin -2147.48364)
		)
		(pad "17" smd rect
			(at -6.09981 -2.59969 90)
			(size 1.79832 0.8001)
			(layers "F.Cu" "F.Mask" "F.Paste")
			(solder_paste_margin -2147.48364)
		)
		(pad "18" smd rect
			(at -6.09981 0.40005 90)
			(size 1.79832 0.8001)
			(layers "F.Cu" "F.Mask" "F.Paste")
			(net "SDA_SPI_CS_N")
			(solder_paste_margin -2147.48364)
		)
		(pad "19" smd rect
			(at -6.09981 1.49987 90)
			(size 1.79832 0.8001)
			(layers "F.Cu" "F.Mask" "F.Paste")
			(net "SCL_SPI_CLK")
			(solder_paste_margin -2147.48364)
		)
		(pad "20" smd rect
			(at -6.09981 2.59969 90)
			(size 1.79832 0.8001)
			(layers "F.Cu" "F.Mask" "F.Paste")
			(net "TX_GPS")
			(solder_paste_margin -2147.48364)
		)
		(pad "21" smd rect
			(at -6.09981 3.69951 90)
			(size 1.79832 0.8001)
			(layers "F.Cu" "F.Mask" "F.Paste")
			(net "RX_GPS")
			(solder_paste_margin -2147.48364)
		)
		(pad "22" smd rect
			(at -6.09981 4.79933 90)
			(size 1.79832 0.8001)
			(layers "F.Cu" "F.Mask" "F.Paste")
			(net "+3V3")
			(solder_paste_margin -2147.48364)
		)
		(pad "23" smd rect
			(at -6.09981 5.89915 90)
			(size 1.79832 0.8001)
			(layers "F.Cu" "F.Mask" "F.Paste")
			(net "+3V3")
			(solder_paste_margin -2147.48364)
		)
		(pad "24" smd rect
			(at -6.09981 6.99897 90)
			(size 1.79832 0.8001)
			(layers "F.Cu" "F.Mask" "F.Paste")
			(net "GND")
			(solder_paste_margin -2147.48364)
		)
	)
)
